# S9S_MB_2U (Grand Teton) — schematic netlist excerpt (pin names and nets, part order shuffled) for the footprints in the layout excerpt that follows; sources: Cadence DE-HDL packaged netlist, KiCad conversion of 03242023_DA0F0TMBIJ0_F0T_Motherboard_J_brd_V01_OCP.brd

J19  SCONN288_ADR50017P130CC  SCONN288_ADR50017-P130CC IO  pkg DDR288S_1-1VXB  page 100
  VIN_BULK0  = P12V_S3_AUX_CPU1_NVDIMM
  RFU0  = TP_CHB_CPU1_DIMM1_FRU_0
  VIN_MGMT  = P3V3_AUX
  HSCL  = I3C_SPD_DDRABCD_CPU1_LVC1_SCL_2
  HSDA  = I3C_SPD_DDRABCD_CPU1_LVC1_SDA
  VSS0  = GND
  DQ0_A  = M_B_CPU1_SA_DQ<0>
  VSS1  = GND
  DQ1_A  = M_B_CPU1_SA_DQ<1>
  VSS2  = GND
  DQS0_A_T  = M_B_CPU1_SA_DQS_DP<0>
  DQS0_A_C  = M_B_CPU1_SA_DQS_DN<0>
  VSS3  = GND
  DQ4_A  = M_B_CPU1_SA_DQ<4>
  VSS4  = GND
  DQ5_A  = M_B_CPU1_SA_DQ<5>
  VSS5  = GND
  DQ8_A  = M_B_CPU1_SA_DQ<8>
  VSS6  = GND
  DQ9_A  = M_B_CPU1_SA_DQ<9>
  VSS7  = GND
  DQS1_A_T  = M_B_CPU1_SA_DQS_DP<1>
  DQS1_A_C  = M_B_CPU1_SA_DQS_DN<1>
  VSS8  = GND
  DQ12_A  = M_B_CPU1_SA_DQ<12>
  VSS9  = GND
  DQ13_A  = M_B_CPU1_SA_DQ<13>
  VSS10  = GND
  DQ16_A  = M_B_CPU1_SA_DQ<16>
  VSS11  = GND
  DQ17_A  = M_B_CPU1_SA_DQ<17>
  VSS12  = GND
  DQS2_A_T  = M_B_CPU1_SA_DQS_DP<2>
  DQS2_A_C  = M_B_CPU1_SA_DQS_DN<2>
  VSS13  = GND
  DQ20_A  = M_B_CPU1_SA_DQ<20>
  VSS14  = GND
  DQ21_A  = M_B_CPU1_SA_DQ<21>
  VSS15  = GND
  DQ24_A  = M_B_CPU1_SA_DQ<24>
  VSS16  = GND
  DQ25_A  = M_B_CPU1_SA_DQ<25>
  VSS17  = GND
  DQS3_A_T  = M_B_CPU1_SA_DQS_DP<3>
  DQS3_A_C  = M_B_CPU1_SA_DQS_DN<3>
  VSS18  = GND
  DQ28_A  = M_B_CPU1_SA_DQ<28>
  VSS19  = GND
  DQ29_A  = M_B_CPU1_SA_DQ<29>
  VSS20  = GND
  CB0_A  = M_B_CPU1_SA_CB<0>
  VSS21  = GND
  CB1_A  = M_B_CPU1_SA_CB<1>
  VSS22  = GND
  DQS4_A_T  = M_B_CPU1_SA_DQS_DP<4>
  DQS4_A_C  = M_B_CPU1_SA_DQS_DN<4>
  VSS23  = GND
  CB4_A  = M_B_CPU1_SA_CB<4>
  VSS24  = GND
  CB5_A  = M_B_CPU1_SA_CB<5>
  VSS25  = GND
  ALERT_N  = M_B_CPU1_ALERT_N
  VSS26  = GND
  CS0_A_N  = M_B_CPU1_SA_CS_N<0>
  VSS27  = GND
  CA0_A  = M_B_CPU1_SA_CA<0>
  VSS28  = GND
  CA2_A  = M_B_CPU1_SA_CA<2>
  VSS29  = GND
  CA4_A  = M_B_CPU1_SA_CA<4>
  VSS30  = GND
  CA6_A  = M_B_CPU1_SA_CA<6>
  VSS31  = GND
  PAR_A  = M_B_CPU1_SA_PAR
  VSS32  = GND
  CA0_B  = M_B_CPU1_SB_CA<0>
  VSS33  = GND
  CA2_B  = M_B_CPU1_SB_CA<2>
  VSS34  = GND
  CA4_B  = M_B_CPU1_SB_CA<4>
  VSS35  = GND
  CA6_B  = M_B_CPU1_SB_CA<6>
  VSS36  = GND
  CS0_B_N  = M_B_CPU1_SB_CS_N<0>
  VSS37  = GND
  \lbd||rsp_a_n\  = M_B_CPU1_SA_RSP<0>
  \lbs||rsp_b_n\  = M_B_CPU1_SB_RSP<0>
  VSS38  = GND
  CB4_B  = M_B_CPU1_SB_CB<4>
  VSS39  = GND
  CB5_B  = M_B_CPU1_SB_CB<5>
  VSS40  = GND
  \dqs9_b_t||tdqs9_b_t||dbi4_b_n\  = M_B_CPU1_SB_DQS_DP<9>
  \dqs9_b_c||tdqs9_b_c\  = M_B_CPU1_SB_DQS_DN<9>
  VSS41  = GND
  CB0_B  = M_B_CPU1_SB_CB<0>
  VSS42  = GND
  CB1_B  = M_B_CPU1_SB_CB<1>
  VSS43  = GND
  DQ0_B  = M_B_CPU1_SB_DQ<0>
  VSS44  = GND
  DQ1_B  = M_B_CPU1_SB_DQ<1>
  VSS45  = GND
  DQS0_B_T  = M_B_CPU1_SB_DQS_DP<0>
  DQS0_B_C  = M_B_CPU1_SB_DQS_DN<0>
  VSS46  = GND
  DQ4_B  = M_B_CPU1_SB_DQ<4>
  VSS47  = GND
  DQ5_B  = M_B_CPU1_SB_DQ<5>
  VSS48  = GND
  DQ8_B  = M_B_CPU1_SB_DQ<8>
  VSS49  = GND
  DQ9_B  = M_B_CPU1_SB_DQ<9>
  VSS50  = GND
  DQS1_B_T  = M_B_CPU1_SB_DQS_DP<1>
  DQS1_B_C  = M_B_CPU1_SB_DQS_DN<1>
  VSS51  = GND
  DQ12_B  = M_B_CPU1_SB_DQ<12>
  VSS52  = GND
  DQ13_B  = M_B_CPU1_SB_DQ<13>
  VSS53  = GND
  DQ16_B  = M_B_CPU1_SB_DQ<16>
  VSS54  = GND
  DQ17_B  = M_B_CPU1_SB_DQ<17>
  VSS55  = GND
  DQS2_B_T  = M_B_CPU1_SB_DQS_DP<2>
  DQS2_B_C  = M_B_CPU1_SB_DQS_DN<2>
  VSS56  = GND
  DQ20_B  = M_B_CPU1_SB_DQ<20>
  VSS57  = GND
  DQ21_B  = M_B_CPU1_SB_DQ<21>
  VSS58  = GND
  DQ24_B  = M_B_CPU1_SB_DQ<24>
  VSS59  = GND
  DQ25_B  = M_B_CPU1_SB_DQ<25>
  VSS60  = GND
  DQS3_B_T  = M_B_CPU1_SB_DQS_DP<3>
  DQS3_B_C  = M_B_CPU1_SB_DQS_DN<3>
  VSS61  = GND
  DQ28_B  = M_B_CPU1_SB_DQ<28>
  VSS62  = GND
  DQ29_B  = M_B_CPU1_SB_DQ<29>
  VSS63  = GND
  RFU1  = TP_CHB_CPU1_DIMM1_FRU_1
  VIN_BULK1  = P12V_S3_AUX_CPU1_NVDIMM
  VIN_BULK2  = P12V_S3_AUX_CPU1_NVDIMM
  \pwr_good||fail_n\  = PWRGD_CHB_CPU1_DIMM1
  HSA  = PD_CHB_CPU1_DIMM1_SAA
  RFU2  = TP_CHB_CPU1_DIMM1_FRU_2
  RFU3  = TP_CHB_CPU1_DIMM1_FRU_3
  VSS64  = GND
  DQ2_A  = M_B_CPU1_SA_DQ<2>
  VSS65  = GND
  DQ3_A  = M_B_CPU1_SA_DQ<3>
  VSS66  = GND
  \dqs5_a_c||tdqs5_a_c||dqs5_a_t||tdqs5_a_t\  = M_B_CPU1_SA_DQS_DN<5>
  \dqs5_a_t||tdqs5_a_t\  = M_B_CPU1_SA_DQS_DP<5>
  VSS67  = GND
  DQ6_A  = M_B_CPU1_SA_DQ<6>
  VSS68  = GND
  DQ7_A  = M_B_CPU1_SA_DQ<7>
  VSS69  = GND
  DQ10_A  = M_B_CPU1_SA_DQ<10>
  VSS70  = GND
  DQ11_A  = M_B_CPU1_SA_DQ<11>
  VSS71  = GND
  \dqs6_a_c||tdqs6_a_c||dqs6_a_t||tdqs6_a_t\  = M_B_CPU1_SA_DQS_DN<6>
  \dqs6_a_t||tdqs6_a_t\  = M_B_CPU1_SA_DQS_DP<6>
  VSS72  = GND
  DQ14_A  = M_B_CPU1_SA_DQ<14>
  VSS73  = GND
  DQ15_A  = M_B_CPU1_SA_DQ<15>
  VSS74  = GND
  DQ18_A  = M_B_CPU1_SA_DQ<18>
  VSS75  = GND
  DQ19_A  = M_B_CPU1_SA_DQ<19>
  VSS76  = GND
  \dqs7_a_c||tdqs7_a_c\  = M_B_CPU1_SA_DQS_DN<7>
  \dqs7_a_t||tdqs7_a_t\  = M_B_CPU1_SA_DQS_DP<7>
  VSS77  = GND
  DQ22_A  = M_B_CPU1_SA_DQ<22>
  VSS78  = GND
  DQ23_A  = M_B_CPU1_SA_DQ<23>
  VSS79  = GND
  DQ26_A  = M_B_CPU1_SA_DQ<26>
  VSS80  = GND
  DQ27_A  = M_B_CPU1_SA_DQ<27>
  VSS81  = GND
  \dqs8_a_c||tdqs8_a_c\  = M_B_CPU1_SA_DQS_DN<8>
  \dqs8_a_t||tdqs8_a_t\  = M_B_CPU1_SA_DQS_DP<8>
  VSS82  = GND
  DQ30_A  = M_B_CPU1_SA_DQ<30>
  VSS83  = GND
  DQ31_A  = M_B_CPU1_SA_DQ<31>
  VSS84  = GND
  CB2_A  = M_B_CPU1_SA_CB<2>
  VSS85  = GND
  CB3_A  = M_B_CPU1_SA_CB<3>
  VSS86  = GND
  \dqs9_a_c||tdqs9_a_c\  = M_B_CPU1_SA_DQS_DN<9>
  \dqs9_a_t||tdqs9_a_t\  = M_B_CPU1_SA_DQS_DP<9>
  VSS87  = GND
  CB6_A  = M_B_CPU1_SA_CB<6>
  VSS88  = GND
  CB7_A  = M_B_CPU1_SA_CB<7>
  VSS89  = GND
  RESET_N  = RST_M_AB_CPU1_FPGA_N
  VSS90  = GND
  CS1_A_N  = M_B_CPU1_SA_CS_N<1>
  VSS91  = GND
  CA1_A  = M_B_CPU1_SA_CA<1>
  VSS92  = GND
  CA3_A  = M_B_CPU1_SA_CA<3>
  VSS93  = GND
  CA5_A  = M_B_CPU1_SA_CA<5>
  VSS94  = GND
  CK_T  = M_B_CPU1_CLK_DP<0>
  CK_C  = M_B_CPU1_CLK_DN<0>
  VSS95  = GND
  RFU4  = TP_CHB_CPU1_DIMM1_FRU_4
  CA1_B  = M_B_CPU1_SB_CA<1>
  VSS96  = GND
  CA3_B  = M_B_CPU1_SB_CA<3>
  VSS97  = GND
  CA5_B  = M_B_CPU1_SB_CA<5>
  VSS98  = GND
  PAR_B  = M_B_CPU1_SB_PAR
  VSS99  = GND
  CS1_B_N  = M_B_CPU1_SB_CS_N<1>
  VSS100  = GND
  RFU5  = TP_CHB_CPU1_DIMM1_FRU_5
  RFU6  = TP_CHB_CPU1_DIMM1_FRU_6
  VSS101  = GND
  CB6_B  = M_B_CPU1_SB_CB<6>
  VSS102  = GND
  CB7_B  = M_B_CPU1_SB_CB<7>
  VSS103  = GND
  DQS4_B_C  = M_B_CPU1_SB_DQS_DN<4>
  DQS4_B_T  = M_B_CPU1_SB_DQS_DP<4>
  VSS104  = GND
  CB2_B  = M_B_CPU1_SB_CB<2>
  VSS105  = GND
  CB3_B  = M_B_CPU1_SB_CB<3>
  VSS106  = GND
  DQ2_B  = M_B_CPU1_SB_DQ<2>
  VSS107  = GND
  DQ3_B  = M_B_CPU1_SB_DQ<3>
  VSS108  = GND
  \dqs5_b_c||tdqs5_b_c\  = M_B_CPU1_SB_DQS_DN<5>
  \dqs5_b_t||tdqs5_b_t\  = M_B_CPU1_SB_DQS_DP<5>
  VSS109  = GND
  DQ6_B  = M_B_CPU1_SB_DQ<6>
  VSS110  = GND
  DQ7_B  = M_B_CPU1_SB_DQ<7>
  VSS111  = GND
  DQ10_B  = M_B_CPU1_SB_DQ<10>
  VSS112  = GND
  DQ11_B  = M_B_CPU1_SB_DQ<11>
  VSS113  = GND
  \dqs6_b_c||tdqs6_b_c\  = M_B_CPU1_SB_DQS_DN<6>
  \dqs6_b_t||tdqs6_b_t\  = M_B_CPU1_SB_DQS_DP<6>
  VSS114  = GND
  DQ14_B  = M_B_CPU1_SB_DQ<14>
  VSS115  = GND
  DQ15_B  = M_B_CPU1_SB_DQ<15>
  VSS116  = GND
  DQ18_B  = M_B_CPU1_SB_DQ<18>
  VSS117  = GND
  DQ19_B  = M_B_CPU1_SB_DQ<19>
  VSS118  = GND
  \dqs7_b_c||tdqs7_b_c\  = M_B_CPU1_SB_DQS_DN<7>
  \dqs7_b_t||tdqs7_b_t\  = M_B_CPU1_SB_DQS_DP<7>
  VSS119  = GND
  DQ22_B  = M_B_CPU1_SB_DQ<22>
  VSS120  = GND
  DQ23_B  = M_B_CPU1_SB_DQ<23>
  VSS121  = GND
  DQ26_B  = M_B_CPU1_SB_DQ<26>
  VSS122  = GND
  DQ27_B  = M_B_CPU1_SB_DQ<27>
  VSS123  = GND
  \dqs8_b_c||tdqs8_b_c\  = M_B_CPU1_SB_DQS_DN<8>
  \dqs8_b_t||tdqs8_b_t\  = M_B_CPU1_SB_DQS_DP<8>
  VSS124  = GND
  DQ30_B  = M_B_CPU1_SB_DQ<30>
  VSS125  = GND
  DQ31_B  = M_B_CPU1_SB_DQ<31>
  VSS126  = GND
  G1  = GND
  G2  = GND
  G3  = GND

(kicad_pcb
	(version 20260206)
	(generator "pcbnew")
	(generator_version "10.0")
	(general
		(thickness 1.6)
		(legacy_teardrops no)
	)
	(paper "A4")
	(title_block
		(title "03242023_DA0F0TMBIJ0_F0T_Motherboard_J_brd_V01_OCP.brd")
		(comment 1 "Grand Teton / footprint 2188 of 6105 (J19), pads 138-182 of 291")
	)
	(layers
		(0 "F.Cu" signal "TOP")
		(4 "In1.Cu" signal "GND")
		(6 "In2.Cu" signal "IN1")
		(8 "In3.Cu" signal "GND1")
		(10 "In4.Cu" signal "IN2")
		(12 "In5.Cu" signal "GND2")
		(14 "In6.Cu" signal "IN3")
		(16 "In7.Cu" signal "GND3")
		(18 "In8.Cu" signal "VCC")
		(20 "In9.Cu" signal "VCC1")
		(22 "In10.Cu" signal "GND4")
		(24 "In11.Cu" signal "IN4")
		(26 "In12.Cu" signal "GND5")
		(28 "In13.Cu" signal "IN5")
		(30 "In14.Cu" signal "GND6")
		(32 "In15.Cu" signal "IN6")
		(34 "In16.Cu" signal "GND7")
		(2 "B.Cu" signal "BOTTOM")
		(9 "F.Adhes" user "F.Adhesive")
		(11 "B.Adhes" user "B.Adhesive")
		(13 "F.Paste" user "Package Geometry/Pastemask Top")
		(15 "B.Paste" user "Package Geometry/Pastemask Bottom")
		(5 "F.SilkS" user "Ref Des/Silkscreen Top")
		(7 "B.SilkS" user "Ref Des/Silkscreen Bottom")
		(1 "F.Mask" user "Board Geometry/Soldermask Top")
		(3 "B.Mask" user "Board Geometry/Soldermask Bottom")
		(17 "Dwgs.User" user "User.Drawings")
		(19 "Cmts.User" user "User.Comments")
		(21 "Eco1.User" user "User.Eco1")
		(23 "Eco2.User" user "User.Eco2")
		(25 "Edge.Cuts" user "Board Geometry/Outline")
		(27 "Margin" user)
		(31 "F.CrtYd" user "Package Geometry/Place Bound Top")
		(29 "B.CrtYd" user "Package Geometry/Place Bound Bottom")
		(35 "F.Fab" user "Ref Des/Assembly Top")
		(33 "B.Fab" user "Ref Des/Assembly Bottom")
	)
	(footprint ""
		(layer "F.Cu")
		(at 40.36568 -258.091686)
		(property "Reference" "J19"
			(at -5.21716 -81.970372 0)
			(unlocked yes)
			(layer "F.SilkS")
			(effects
				(font
					(size 0.7874 0.5842)
					(thickness 0.1524)
				)
				(justify left)
			)
		)
		(property "Value" ""
			(at 0 0 0)
			(layer "F.Fab")
			(effects
				(font
					(size 1.27 1.27)
				)
			)
		)
		(duplicate_pad_numbers_are_jumpers no)
		(pad "138" smd rect
			(at -2.050034 58.224928 270)
			(size 0.519938 1.4986)
			(layers "F.Cu" "F.Mask" "F.Paste")
			(net "M_B_CPU1_SB_DQS_DN<3>")
		)
		(pad "139" smd rect
			(at -2.050034 59.075066 270)
			(size 0.519938 1.4986)
			(layers "F.Cu" "F.Mask" "F.Paste")
			(net "GND")
		)
		(pad "140" smd rect
			(at -2.050034 59.92495 270)
			(size 0.519938 1.4986)
			(layers "F.Cu" "F.Mask" "F.Paste")
			(net "M_B_CPU1_SB_DQ<28>")
		)
		(pad "141" smd rect
			(at -2.050034 60.775088 270)
			(size 0.519938 1.4986)
			(layers "F.Cu" "F.Mask" "F.Paste")
			(net "GND")
		)
		(pad "142" smd rect
			(at -2.050034 61.624972 270)
			(size 0.519938 1.4986)
			(layers "F.Cu" "F.Mask" "F.Paste")
			(net "M_B_CPU1_SB_DQ<29>")
		)
		(pad "143" smd rect
			(at -2.050034 62.47511 270)
			(size 0.519938 1.4986)
			(layers "F.Cu" "F.Mask" "F.Paste")
			(net "GND")
		)
		(pad "144" smd rect
			(at -2.050034 63.324994 270)
			(size 0.519938 1.4986)
			(layers "F.Cu" "F.Mask" "F.Paste")
			(net "TP_CHB_CPU1_DIMM1_FRU_1")
		)
		(pad "145" smd rect
			(at 2.050034 -63.324994 270)
			(size 0.519938 1.4986)
			(layers "F.Cu" "F.Mask" "F.Paste")
			(net "P12V_S3_AUX_CPU1_NVDIMM")
		)
		(pad "146" smd rect
			(at 2.050034 -62.47511 270)
			(size 0.519938 1.4986)
			(layers "F.Cu" "F.Mask" "F.Paste")
			(net "P12V_S3_AUX_CPU1_NVDIMM")
		)
		(pad "147" smd rect
			(at 2.050034 -61.624972 270)
			(size 0.519938 1.4986)
			(layers "F.Cu" "F.Mask" "F.Paste")
			(net "PWRGD_CHB_CPU1_DIMM1")
		)
		(pad "148" smd rect
			(at 2.050034 -60.775088 270)
			(size 0.519938 1.4986)
			(layers "F.Cu" "F.Mask" "F.Paste")
			(net "PD_CHB_CPU1_DIMM1_SAA")
		)
		(pad "149" smd rect
			(at 2.050034 -59.92495 270)
			(size 0.519938 1.4986)
			(layers "F.Cu" "F.Mask" "F.Paste")
			(net "TP_CHB_CPU1_DIMM1_FRU_2")
		)
		(pad "150" smd rect
			(at 2.050034 -59.075066 270)
			(size 0.519938 1.4986)
			(layers "F.Cu" "F.Mask" "F.Paste")
			(net "TP_CHB_CPU1_DIMM1_FRU_3")
		)
		(pad "151" smd rect
			(at 2.050034 -58.224928 270)
			(size 0.519938 1.4986)
			(layers "F.Cu" "F.Mask" "F.Paste")
			(net "GND")
		)
		(pad "152" smd rect
			(at 2.050034 -57.375044 270)
			(size 0.519938 1.4986)
			(layers "F.Cu" "F.Mask" "F.Paste")
			(net "M_B_CPU1_SA_DQ<2>")
		)
		(pad "153" smd rect
			(at 2.050034 -56.524906 270)
			(size 0.519938 1.4986)
			(layers "F.Cu" "F.Mask" "F.Paste")
			(net "GND")
		)
		(pad "154" smd rect
			(at 2.050034 -55.675022 270)
			(size 0.519938 1.4986)
			(layers "F.Cu" "F.Mask" "F.Paste")
			(net "M_B_CPU1_SA_DQ<3>")
		)
		(pad "155" smd rect
			(at 2.050034 -54.824884 270)
			(size 0.519938 1.4986)
			(layers "F.Cu" "F.Mask" "F.Paste")
			(net "GND")
		)
		(pad "156" smd rect
			(at 2.050034 -53.975 270)
			(size 0.519938 1.4986)
			(layers "F.Cu" "F.Mask" "F.Paste")
			(net "M_B_CPU1_SA_DQS_DN<5>")
		)
		(pad "157" smd rect
			(at 2.050034 -53.125116 270)
			(size 0.519938 1.4986)
			(layers "F.Cu" "F.Mask" "F.Paste")
			(net "M_B_CPU1_SA_DQS_DP<5>")
		)
		(pad "158" smd rect
			(at 2.050034 -52.274978 270)
			(size 0.519938 1.4986)
			(layers "F.Cu" "F.Mask" "F.Paste")
			(net "GND")
		)
		(pad "159" smd rect
			(at 2.050034 -51.425094 270)
			(size 0.519938 1.4986)
			(layers "F.Cu" "F.Mask" "F.Paste")
			(net "M_B_CPU1_SA_DQ<6>")
		)
		(pad "160" smd rect
			(at 2.050034 -50.574956 270)
			(size 0.519938 1.4986)
			(layers "F.Cu" "F.Mask" "F.Paste")
			(net "GND")
		)
		(pad "161" smd rect
			(at 2.050034 -49.725072 270)
			(size 0.519938 1.4986)
			(layers "F.Cu" "F.Mask" "F.Paste")
			(net "M_B_CPU1_SA_DQ<7>")
		)
		(pad "162" smd rect
			(at 2.050034 -48.874934 270)
			(size 0.519938 1.4986)
			(layers "F.Cu" "F.Mask" "F.Paste")
			(net "GND")
		)
		(pad "163" smd rect
			(at 2.050034 -48.02505 270)
			(size 0.519938 1.4986)
			(layers "F.Cu" "F.Mask" "F.Paste")
			(net "M_B_CPU1_SA_DQ<10>")
		)
		(pad "164" smd rect
			(at 2.050034 -47.174912 270)
			(size 0.519938 1.4986)
			(layers "F.Cu" "F.Mask" "F.Paste")
			(net "GND")
		)
		(pad "165" smd rect
			(at 2.050034 -46.325028 270)
			(size 0.519938 1.4986)
			(layers "F.Cu" "F.Mask" "F.Paste")
			(net "M_B_CPU1_SA_DQ<11>")
		)
		(pad "166" smd rect
			(at 2.050034 -45.47489 270)
			(size 0.519938 1.4986)
			(layers "F.Cu" "F.Mask" "F.Paste")
			(net "GND")
		)
		(pad "167" smd rect
			(at 2.050034 -44.625006 270)
			(size 0.519938 1.4986)
			(layers "F.Cu" "F.Mask" "F.Paste")
			(net "M_B_CPU1_SA_DQS_DN<6>")
		)
		(pad "168" smd rect
			(at 2.050034 -43.775122 270)
			(size 0.519938 1.4986)
			(layers "F.Cu" "F.Mask" "F.Paste")
			(net "M_B_CPU1_SA_DQS_DP<6>")
		)
		(pad "169" smd rect
			(at 2.050034 -42.924984 270)
			(size 0.519938 1.4986)
			(layers "F.Cu" "F.Mask" "F.Paste")
			(net "GND")
		)
		(pad "170" smd rect
			(at 2.050034 -42.0751 270)
			(size 0.519938 1.4986)
			(layers "F.Cu" "F.Mask" "F.Paste")
			(net "M_B_CPU1_SA_DQ<14>")
		)
		(pad "171" smd rect
			(at 2.050034 -41.224962 270)
			(size 0.519938 1.4986)
			(layers "F.Cu" "F.Mask" "F.Paste")
			(net "GND")
		)
		(pad "172" smd rect
			(at 2.050034 -40.375078 270)
			(size 0.519938 1.4986)
			(layers "F.Cu" "F.Mask" "F.Paste")
			(net "M_B_CPU1_SA_DQ<15>")
		)
		(pad "173" smd rect
			(at 2.050034 -39.52494 270)
			(size 0.519938 1.4986)
			(layers "F.Cu" "F.Mask" "F.Paste")
			(net "GND")
		)
		(pad "174" smd rect
			(at 2.050034 -38.675056 270)
			(size 0.519938 1.4986)
			(layers "F.Cu" "F.Mask" "F.Paste")
			(net "M_B_CPU1_SA_DQ<18>")
		)
		(pad "175" smd rect
			(at 2.050034 -37.824918 270)
			(size 0.519938 1.4986)
			(layers "F.Cu" "F.Mask" "F.Paste")
			(net "GND")
		)
		(pad "176" smd rect
			(at 2.050034 -36.975034 270)
			(size 0.519938 1.4986)
			(layers "F.Cu" "F.Mask" "F.Paste")
			(net "M_B_CPU1_SA_DQ<19>")
		)
		(pad "177" smd rect
			(at 2.050034 -36.124896 270)
			(size 0.519938 1.4986)
			(layers "F.Cu" "F.Mask" "F.Paste")
			(net "GND")
		)
		(pad "178" smd rect
			(at 2.050034 -35.275012 270)
			(size 0.519938 1.4986)
			(layers "F.Cu" "F.Mask" "F.Paste")
			(net "M_B_CPU1_SA_DQS_DN<7>")
		)
		(pad "179" smd rect
			(at 2.050034 -34.425128 270)
			(size 0.519938 1.4986)
			(layers "F.Cu" "F.Mask" "F.Paste")
			(net "M_B_CPU1_SA_DQS_DP<7>")
		)
		(pad "180" smd rect
			(at 2.050034 -33.57499 270)
			(size 0.519938 1.4986)
			(layers "F.Cu" "F.Mask" "F.Paste")
			(net "GND")
		)
		(pad "181" smd rect
			(at 2.050034 -32.725106 270)
			(size 0.519938 1.4986)
			(layers "F.Cu" "F.Mask" "F.Paste")
			(net "M_B_CPU1_SA_DQ<22>")
		)
		(pad "182" smd rect
			(at 2.050034 -31.874968 270)
			(size 0.519938 1.4986)
			(layers "F.Cu" "F.Mask" "F.Paste")
			(net "GND")
		)
	)
)
